(kicad_pcb
	(version 20260206)
	(generator "pcbnew")
	(generator_version "10.0")
	(general
		(thickness 1.6)
		(legacy_teardrops no)
	)
	(paper "A4")
	(title_block
		(title "panther-plus-userver — 13130-1b_20150205.brd")
		(comment 1 "Honey Badger (Wiwynn) / footprints 625-631 of 1509")
	)
	(layers
		(0 "F.Cu" signal "TOP")
		(4 "In1.Cu" signal "L2")
		(6 "In2.Cu" signal "L3")
		(8 "In3.Cu" signal "L4")
		(10 "In4.Cu" signal "L5")
		(12 "In5.Cu" signal "L6")
		(14 "In6.Cu" signal "L7")
		(16 "In7.Cu" signal "L8")
		(18 "In8.Cu" signal "L9")
		(20 "In9.Cu" signal "L10")
		(22 "In10.Cu" signal "L11")
		(2 "B.Cu" signal "BOTTOM")
		(9 "F.Adhes" user "F.Adhesive")
		(11 "B.Adhes" user "B.Adhesive")
		(13 "F.Paste" user "Package Geometry/Pastemask Top")
		(15 "B.Paste" user "Package Geometry/Pastemask Bottom")
		(5 "F.SilkS" user "Ref Des/Silkscreen Top")
		(7 "B.SilkS" user "Ref Des/Silkscreen Bottom")
		(1 "F.Mask" user "Board Geometry/Soldermask Top")
		(3 "B.Mask" user "Board Geometry/Soldermask Bottom")
		(17 "Dwgs.User" user "User.Drawings")
		(19 "Cmts.User" user "User.Comments")
		(21 "Eco1.User" user "User.Eco1")
		(23 "Eco2.User" user "User.Eco2")
		(25 "Edge.Cuts" user "Board Geometry/Outline")
		(27 "Margin" user)
		(31 "F.CrtYd" user "Package Geometry/Place Bound Top")
		(29 "B.CrtYd" user "Package Geometry/Place Bound Bottom")
		(35 "F.Fab" user "Ref Des/Assembly Top")
		(33 "B.Fab" user "Ref Des/Assembly Bottom")
	)
	(footprint ""
		(layer "F.Cu")
		(at 27.2542 -66.4972 -90)
		(property "Reference" "PQ2"
			(at 0 0 270)
			(layer "F.SilkS")
			(hide yes)
			(effects
				(font
					(size 1.27 1.27)
				)
			)
		)
		(property "Value" "MMBT3904TT1G-GP"
			(at -2.032 -3.674618 270)
			(unlocked yes)
			(layer "F.Fab")
			(hide yes)
			(effects
				(font
					(size 1.016 1.016)
					(thickness 0.1524)
				)
			)
		)
		(property "Device Type" "SC75CBE1D6H36"
			(at -2.032 -5.198618 270)
			(unlocked yes)
			(layer "F.Fab")
			(hide yes)
			(effects
				(font
					(size 1.016 1.016)
					(thickness 0.1524)
				)
			)
		)
		(duplicate_pad_numbers_are_jumpers no)
		(fp_poly
			(pts
				(xy 0.381 -1.1938) (xy -0.381 -1.1938) (xy -0.381 -0.6604) (xy -1.0541 -0.6604) (xy -1.0541 0.6604)
				(xy -0.889 0.6604) (xy -0.889 1.1938) (xy 0.889 1.1938) (xy 0.889 0.6604) (xy 1.0541 0.6604) (xy 1.0541 -0.6604)
				(xy 0.381 -0.6604)
			)
			(stroke
				(width 0)
				(type default)
			)
			(fill no)
			(layer "F.CrtYd")
		)
		(fp_poly
			(pts
				(xy 0.381 -1.1938) (xy -0.381 -1.1938) (xy -0.381 -0.6604) (xy -1.0541 -0.6604) (xy -1.0541 0.6604)
				(xy -0.889 0.6604) (xy -0.889 1.1938) (xy 0.889 1.1938) (xy 0.889 0.6604) (xy 1.0541 0.6604) (xy 1.0541 -0.6604)
				(xy 0.381 -0.6604)
			)
			(stroke
				(width 0)
				(type default)
			)
			(fill no)
			(layer "F.Fab")
		)
		(pad "B" smd custom
			(at -0.508 0.6604 270)
			(size 0.127 0.127)
			(layers "F.Cu" "F.Mask" "F.Paste")
			(net "VCCP_Z")
			(options
				(clearance outline)
				(anchor circle)
			)
			(primitives
				(gr_poly
					(pts
						(arc
							(start -0.0508 0.4064)
							(mid -0.194484 0.346884)
							(end -0.254 0.2032)
						)
						(arc
							(start -0.254 -0.2032)
							(mid -0.194484 -0.346884)
							(end -0.0508 -0.4064)
						)
						(arc
							(start 0.0508 -0.4064)
							(mid 0.194484 -0.346884)
							(end 0.254 -0.2032)
						)
						(arc
							(start 0.254 0.2032)
							(mid 0.194484 0.346884)
							(end 0.0508 0.4064)
						)
					)
					(width 0)
					(fill yes)
				)
			)
		)
		(pad "C" smd custom
			(at 0 -0.6604 270)
			(size 0.127 0.127)
			(layers "F.Cu" "F.Mask" "F.Paste")
			(net "P12V")
			(options
				(clearance outline)
				(anchor circle)
			)
			(primitives
				(gr_poly
					(pts
						(arc
							(start -0.0508 0.4064)
							(mid -0.194484 0.346884)
							(end -0.254 0.2032)
						)
						(arc
							(start -0.254 -0.2032)
							(mid -0.194484 -0.346884)
							(end -0.0508 -0.4064)
						)
						(arc
							(start 0.0508 -0.4064)
							(mid 0.194484 -0.346884)
							(end 0.254 -0.2032)
						)
						(arc
							(start 0.254 0.2032)
							(mid 0.194484 0.346884)
							(end 0.0508 0.4064)
						)
					)
					(width 0)
					(fill yes)
				)
			)
		)
		(pad "E" smd custom
			(at 0.508 0.6604 270)
			(size 0.127 0.127)
			(layers "F.Cu" "F.Mask" "F.Paste")
			(net "VCCP_5VBIAS")
			(options
				(clearance outline)
				(anchor circle)
			)
			(primitives
				(gr_poly
					(pts
						(arc
							(start -0.0508 0.4064)
							(mid -0.194484 0.346884)
							(end -0.254 0.2032)
						)
						(arc
							(start -0.254 -0.2032)
							(mid -0.194484 -0.346884)
							(end -0.0508 -0.4064)
						)
						(arc
							(start 0.0508 -0.4064)
							(mid 0.194484 -0.346884)
							(end 0.254 -0.2032)
						)
						(arc
							(start 0.254 0.2032)
							(mid 0.194484 0.346884)
							(end 0.0508 0.4064)
						)
					)
					(width 0)
					(fill yes)
				)
			)
		)
	)
	(footprint ""
		(layer "F.Cu")
		(at 20.828 -47.371 90)
		(property "Reference" "PR98"
			(at 0 0 90)
			(layer "F.SilkS")
			(hide yes)
			(effects
				(font
					(size 1.27 1.27)
				)
			)
		)
		(property "Value" "3K65R2F-1-GP"
			(at 1.7907 -1.1176 90)
			(unlocked yes)
			(layer "F.Fab")
			(hide yes)
			(effects
				(font
					(size 1.016 1.016)
					(thickness 0.1524)
				)
			)
		)
		(property "Device Type" "R402H16"
			(at 1.7907 -2.6416 90)
			(unlocked yes)
			(layer "F.Fab")
			(hide yes)
			(effects
				(font
					(size 1.016 1.016)
					(thickness 0.1524)
				)
			)
		)
		(duplicate_pad_numbers_are_jumpers no)
		(fp_rect
			(start -0.381 0.8382)
			(end 0.381 -0.8382)
			(stroke
				(width 0)
				(type default)
			)
			(fill no)
			(layer "F.CrtYd")
		)
		(fp_rect
			(start -0.381 0.8382)
			(end 0.381 -0.8382)
			(stroke
				(width 0)
				(type default)
			)
			(fill no)
			(layer "F.Fab")
		)
		(pad "1" smd custom
			(at 0 -0.4318 90)
			(size 0.127 0.127)
			(layers "F.Cu" "F.Mask" "F.Paste")
			(net "VR_PVCCP_ISUMP_R2")
			(options
				(clearance outline)
				(anchor circle)
			)
			(primitives
				(gr_poly
					(pts
						(arc
							(start -0.2032 -0.2794)
							(mid -0.239121 -0.264521)
							(end -0.254 -0.2286)
						)
						(arc
							(start -0.254 0.2286)
							(mid -0.239121 0.264521)
							(end -0.2032 0.2794)
						)
						(arc
							(start 0.2032 0.2794)
							(mid 0.239121 0.264521)
							(end 0.254 0.2286)
						)
						(arc
							(start 0.254 -0.2286)
							(mid 0.239121 -0.264521)
							(end 0.2032 -0.2794)
						)
					)
					(width 0)
					(fill yes)
				)
			)
		)
		(pad "2" smd custom
			(at 0 0.4318 90)
			(size 0.127 0.127)
			(layers "F.Cu" "F.Mask" "F.Paste")
			(net "VR_PVCCP_ISUMP")
			(options
				(clearance outline)
				(anchor circle)
			)
			(primitives
				(gr_poly
					(pts
						(arc
							(start -0.2032 -0.2794)
							(mid -0.239121 -0.264521)
							(end -0.254 -0.2286)
						)
						(arc
							(start -0.254 0.2286)
							(mid -0.239121 0.264521)
							(end -0.2032 0.2794)
						)
						(arc
							(start 0.2032 0.2794)
							(mid 0.239121 0.264521)
							(end 0.254 0.2286)
						)
						(arc
							(start 0.254 -0.2286)
							(mid 0.239121 -0.264521)
							(end 0.2032 -0.2794)
						)
					)
					(width 0)
					(fill yes)
				)
			)
		)
	)
	(footprint ""
		(layer "F.Cu")
		(at 31.75 -55.118)
		(property "Reference" "PR71"
			(at 0 0 0)
			(layer "F.SilkS")
			(hide yes)
			(effects
				(font
					(size 1.27 1.27)
				)
			)
		)
		(property "Value" "0R2J-2-GP"
			(at 1.7907 -1.1176 0)
			(unlocked yes)
			(layer "F.Fab")
			(hide yes)
			(effects
				(font
					(size 1.016 1.016)
					(thickness 0.1524)
				)
			)
		)
		(property "Device Type" "R402H16"
			(at 1.7907 -2.6416 0)
			(unlocked yes)
			(layer "F.Fab")
			(hide yes)
			(effects
				(font
					(size 1.016 1.016)
					(thickness 0.1524)
				)
			)
		)
		(duplicate_pad_numbers_are_jumpers no)
		(fp_rect
			(start -0.381 0.8382)
			(end 0.381 -0.8382)
			(stroke
				(width 0)
				(type default)
			)
			(fill no)
			(layer "F.CrtYd")
		)
		(fp_rect
			(start -0.381 0.8382)
			(end 0.381 -0.8382)
			(stroke
				(width 0)
				(type default)
			)
			(fill no)
			(layer "F.Fab")
		)
		(pad "1" smd custom
			(at 0 -0.4318)
			(size 0.127 0.127)
			(layers "F.Cu" "F.Mask" "F.Paste")
			(net "VR_FET_SW_P12V_PVCCP_PVNN")
			(options
				(clearance outline)
				(anchor circle)
			)
			(primitives
				(gr_poly
					(pts
						(arc
							(start -0.2032 -0.2794)
							(mid -0.239121 -0.264521)
							(end -0.254 -0.2286)
						)
						(arc
							(start -0.254 0.2286)
							(mid -0.239121 0.264521)
							(end -0.2032 0.2794)
						)
						(arc
							(start 0.2032 0.2794)
							(mid 0.239121 0.264521)
							(end 0.254 0.2286)
						)
						(arc
							(start 0.254 -0.2286)
							(mid 0.239121 -0.264521)
							(end 0.2032 -0.2794)
						)
					)
					(width 0)
					(fill yes)
				)
			)
		)
		(pad "2" smd custom
			(at 0 0.4318)
			(size 0.127 0.127)
			(layers "F.Cu" "F.Mask" "F.Paste")
			(net "VR_PVCCP_PVNN_VIN")
			(options
				(clearance outline)
				(anchor circle)
			)
			(primitives
				(gr_poly
					(pts
						(arc
							(start -0.2032 -0.2794)
							(mid -0.239121 -0.264521)
							(end -0.254 -0.2286)
						)
						(arc
							(start -0.254 0.2286)
							(mid -0.239121 0.264521)
							(end -0.2032 0.2794)
						)
						(arc
							(start 0.2032 0.2794)
							(mid 0.239121 0.264521)
							(end 0.254 0.2286)
						)
						(arc
							(start 0.254 -0.2286)
							(mid 0.239121 -0.264521)
							(end 0.2032 -0.2794)
						)
					)
					(width 0)
					(fill yes)
				)
			)
		)
	)
	(footprint ""
		(layer "F.Cu")
		(at 23.5204 -50.5206)
		(property "Reference" "PR83"
			(at 0 0 0)
			(layer "F.SilkS")
			(hide yes)
			(effects
				(font
					(size 1.27 1.27)
				)
			)
		)
		(property "Value" "10R2F-L-GP"
			(at 1.7907 -1.1176 0)
			(unlocked yes)
			(layer "F.Fab")
			(hide yes)
			(effects
				(font
					(size 1.016 1.016)
					(thickness 0.1524)
				)
			)
		)
		(property "Device Type" "R402H14"
			(at 1.7907 -2.6416 0)
			(unlocked yes)
			(layer "F.Fab")
			(hide yes)
			(effects
				(font
					(size 1.016 1.016)
					(thickness 0.1524)
				)
			)
		)
		(duplicate_pad_numbers_are_jumpers no)
		(fp_rect
			(start -0.381 0.8382)
			(end 0.381 -0.8382)
			(stroke
				(width 0)
				(type default)
			)
			(fill no)
			(layer "F.CrtYd")
		)
		(fp_rect
			(start -0.381 0.8382)
			(end 0.381 -0.8382)
			(stroke
				(width 0)
				(type default)
			)
			(fill no)
			(layer "F.Fab")
		)
		(pad "1" smd custom
			(at 0 -0.4318)
			(size 0.127 0.127)
			(layers "F.Cu" "F.Mask" "F.Paste")
			(net "VR_PVCCP_RTN")
			(options
				(clearance outline)
				(anchor circle)
			)
			(primitives
				(gr_poly
					(pts
						(arc
							(start -0.2032 -0.2794)
							(mid -0.239121 -0.264521)
							(end -0.254 -0.2286)
						)
						(arc
							(start -0.254 0.2286)
							(mid -0.239121 0.264521)
							(end -0.2032 0.2794)
						)
						(arc
							(start 0.2032 0.2794)
							(mid 0.239121 0.264521)
							(end 0.254 0.2286)
						)
						(arc
							(start 0.254 -0.2286)
							(mid 0.239121 -0.264521)
							(end 0.2032 -0.2794)
						)
					)
					(width 0)
					(fill yes)
				)
			)
		)
		(pad "2" smd custom
			(at 0 0.4318)
			(size 0.127 0.127)
			(layers "F.Cu" "F.Mask" "F.Paste")
			(net "GND")
			(options
				(clearance outline)
				(anchor circle)
			)
			(primitives
				(gr_poly
					(pts
						(arc
							(start -0.2032 -0.2794)
							(mid -0.239121 -0.264521)
							(end -0.254 -0.2286)
						)
						(arc
							(start -0.254 0.2286)
							(mid -0.239121 0.264521)
							(end -0.2032 0.2794)
						)
						(arc
							(start 0.2032 0.2794)
							(mid 0.239121 0.264521)
							(end 0.254 0.2286)
						)
						(arc
							(start 0.254 -0.2286)
							(mid 0.239121 -0.264521)
							(end 0.2032 -0.2794)
						)
					)
					(width 0)
					(fill yes)
				)
			)
		)
	)
	(footprint ""
		(layer "F.Cu")
		(at 17.1196 -63.8302 180)
		(property "Reference" "PC24"
			(at 0 0 180)
			(layer "F.SilkS")
			(hide yes)
			(effects
				(font
					(size 1.27 1.27)
				)
			)
		)
		(property "Value" "SCD22U10V2KX-1GP"
			(at 1.8923 -1.2065 180)
			(unlocked yes)
			(layer "F.Fab")
			(hide yes)
			(effects
				(font
					(size 1.016 1.016)
					(thickness 0.1524)
				)
			)
		)
		(property "Device Type" "C402H22"
			(at 1.8923 -2.7305 180)
			(unlocked yes)
			(layer "F.Fab")
			(hide yes)
			(effects
				(font
					(size 1.016 1.016)
					(thickness 0.1524)
				)
			)
		)
		(duplicate_pad_numbers_are_jumpers no)
		(fp_rect
			(start -0.381 0.7366)
			(end 0.381 -0.7366)
			(stroke
				(width 0)
				(type default)
			)
			(fill no)
			(layer "F.CrtYd")
		)
		(fp_rect
			(start -0.381 0.7366)
			(end 0.381 -0.7366)
			(stroke
				(width 0)
				(type default)
			)
			(fill no)
			(layer "F.Fab")
		)
		(pad "1" smd custom
			(at 0 -0.4572 180)
			(size 0.1143 0.1143)
			(layers "F.Cu" "F.Mask" "F.Paste")
			(net "VR_PVNN_IMON")
			(options
				(clearance outline)
				(anchor circle)
			)
			(primitives
				(gr_poly
					(pts
						(arc
							(start -0.254 -0.1778)
							(mid -0.239121 -0.213721)
							(end -0.2032 -0.2286)
						)
						(arc
							(start 0.2032 -0.2286)
							(mid 0.239121 -0.213721)
							(end 0.254 -0.1778)
						)
						(arc
							(start 0.254 0.1778)
							(mid 0.239121 0.213721)
							(end 0.2032 0.2286)
						)
						(arc
							(start -0.2032 0.2286)
							(mid -0.239121 0.213721)
							(end -0.254 0.1778)
						)
					)
					(width 0)
					(fill yes)
				)
			)
		)
		(pad "2" smd custom
			(at 0 0.4572 180)
			(size 0.1143 0.1143)
			(layers "F.Cu" "F.Mask" "F.Paste")
			(net "GND")
			(options
				(clearance outline)
				(anchor circle)
			)
			(primitives
				(gr_poly
					(pts
						(arc
							(start -0.254 -0.1778)
							(mid -0.239121 -0.213721)
							(end -0.2032 -0.2286)
						)
						(arc
							(start 0.2032 -0.2286)
							(mid 0.239121 -0.213721)
							(end 0.254 -0.1778)
						)
						(arc
							(start 0.254 0.1778)
							(mid 0.239121 0.213721)
							(end 0.2032 0.2286)
						)
						(arc
							(start -0.2032 0.2286)
							(mid -0.239121 0.213721)
							(end -0.254 0.1778)
						)
					)
					(width 0)
					(fill yes)
				)
			)
		)
	)
	(footprint ""
		(layer "F.Cu")
		(at 116.967 -36.465002 90)
		(property "Reference" "PR113"
			(at 0 0 90)
			(layer "F.SilkS")
			(hide yes)
			(effects
				(font
					(size 1.27 1.27)
				)
			)
		)
		(property "Value" "0R2J-2-GP"
			(at 0.064008 -3.993896 90)
			(unlocked yes)
			(layer "F.Fab")
			(hide yes)
			(effects
				(font
					(size 1.016 1.016)
					(thickness 0.1524)
				)
			)
		)
		(property "Device Type" "R402H16"
			(at 0.064008 -5.517896 90)
			(unlocked yes)
			(layer "F.Fab")
			(hide yes)
			(effects
				(font
					(size 1.016 1.016)
					(thickness 0.1524)
				)
			)
		)
		(duplicate_pad_numbers_are_jumpers no)
		(fp_rect
			(start -0.381 0.8382)
			(end 0.381 -0.8382)
			(stroke
				(width 0)
				(type default)
			)
			(fill no)
			(layer "F.CrtYd")
		)
		(fp_rect
			(start -0.381 0.8382)
			(end 0.381 -0.8382)
			(stroke
				(width 0)
				(type default)
			)
			(fill no)
			(layer "F.Fab")
		)
		(pad "1" smd custom
			(at 0 -0.4318 90)
			(size 0.127 0.127)
			(layers "F.Cu" "F.Mask" "F.Paste")
			(net "AVV_VCCCPUVIDSIO_1P03_SENSE")
			(options
				(clearance outline)
				(anchor circle)
			)
			(primitives
				(gr_poly
					(pts
						(arc
							(start -0.2032 -0.2794)
							(mid -0.239121 -0.264521)
							(end -0.254 -0.2286)
						)
						(arc
							(start -0.254 0.2286)
							(mid -0.239121 0.264521)
							(end -0.2032 0.2794)
						)
						(arc
							(start 0.2032 0.2794)
							(mid 0.239121 0.264521)
							(end 0.254 0.2286)
						)
						(arc
							(start 0.254 -0.2286)
							(mid 0.239121 -0.264521)
							(end 0.2032 -0.2794)
						)
					)
					(width 0)
					(fill yes)
				)
			)
		)
		(pad "2" smd custom
			(at 0 0.4318 90)
			(size 0.127 0.127)
			(layers "F.Cu" "F.Mask" "F.Paste")
			(net "VR_PVCCP_VSEN")
			(options
				(clearance outline)
				(anchor circle)
			)
			(primitives
				(gr_poly
					(pts
						(arc
							(start -0.2032 -0.2794)
							(mid -0.239121 -0.264521)
							(end -0.254 -0.2286)
						)
						(arc
							(start -0.254 0.2286)
							(mid -0.239121 0.264521)
							(end -0.2032 0.2794)
						)
						(arc
							(start 0.2032 0.2794)
							(mid 0.239121 0.264521)
							(end 0.254 0.2286)
						)
						(arc
							(start 0.254 -0.2286)
							(mid 0.239121 -0.264521)
							(end 0.2032 -0.2794)
						)
					)
					(width 0)
					(fill yes)
				)
			)
		)
	)
	(footprint ""
		(layer "F.Cu")
		(at 187.3758 -28.2194 90)
		(property "Reference" "PC107"
			(at 0 0 90)
			(layer "F.SilkS")
			(hide yes)
			(effects
				(font
					(size 1.27 1.27)
				)
			)
		)
		(property "Value" "SCD068U16V2KX-GP"
			(at 1.8923 -1.2065 90)
			(unlocked yes)
			(layer "F.Fab")
			(hide yes)
			(effects
				(font
					(size 1.016 1.016)
					(thickness 0.1524)
				)
			)
		)
		(property "Device Type" "C402H22"
			(at 1.8923 -2.7305 90)
			(unlocked yes)
			(layer "F.Fab")
			(hide yes)
			(effects
				(font
					(size 1.016 1.016)
					(thickness 0.1524)
				)
			)
		)
		(duplicate_pad_numbers_are_jumpers no)
		(fp_rect
			(start -0.381 0.7366)
			(end 0.381 -0.7366)
			(stroke
				(width 0)
				(type default)
			)
			(fill no)
			(layer "F.CrtYd")
		)
		(fp_rect
			(start -0.381 0.7366)
			(end 0.381 -0.7366)
			(stroke
				(width 0)
				(type default)
			)
			(fill no)
			(layer "F.Fab")
		)
		(pad "1" smd custom
			(at 0 -0.4572 90)
			(size 0.1143 0.1143)
			(layers "F.Cu" "F.Mask" "F.Paste")
			(net "VR_PVDDR_A_VSEN")
			(options
				(clearance outline)
				(anchor circle)
			)
			(primitives
				(gr_poly
					(pts
						(arc
							(start -0.254 -0.1778)
							(mid -0.239121 -0.213721)
							(end -0.2032 -0.2286)
						)
						(arc
							(start 0.2032 -0.2286)
							(mid 0.239121 -0.213721)
							(end 0.254 -0.1778)
						)
						(arc
							(start 0.254 0.1778)
							(mid 0.239121 0.213721)
							(end 0.2032 0.2286)
						)
						(arc
							(start -0.2032 0.2286)
							(mid -0.239121 0.213721)
							(end -0.254 0.1778)
						)
					)
					(width 0)
					(fill yes)
				)
			)
		)
		(pad "2" smd custom
			(at 0 0.4572 90)
			(size 0.1143 0.1143)
			(layers "F.Cu" "F.Mask" "F.Paste")
			(net "VSENSE_PVDDR_A_VRTN")
			(options
				(clearance outline)
				(anchor circle)
			)
			(primitives
				(gr_poly
					(pts
						(arc
							(start -0.254 -0.1778)
							(mid -0.239121 -0.213721)
							(end -0.2032 -0.2286)
						)
						(arc
							(start 0.2032 -0.2286)
							(mid 0.239121 -0.213721)
							(end 0.254 -0.1778)
						)
						(arc
							(start 0.254 0.1778)
							(mid 0.239121 0.213721)
							(end 0.2032 0.2286)
						)
						(arc
							(start -0.2032 0.2286)
							(mid -0.239121 0.213721)
							(end -0.254 0.1778)
						)
					)
					(width 0)
					(fill yes)
				)
			)
		)
	)
)
